(kicad_pcb
	(version 20241229)
	(generator "pcbnew")
	(generator_version "9.0")
	(general
		(thickness 1.599998)
		(legacy_teardrops no)
	)
	(paper "A4")
	(title_block
		(date "2023-02-12")
		(rev "1.1.5")
		(comment 9 "footprints 109-113 of 473")
	)
	(layers
		(0 "F.Cu" signal)
		(4 "In1.Cu" power "In1.GND")
		(6 "In2.Cu" signal)
		(8 "In3.Cu" power "In3.GND")
		(10 "In4.Cu" power "In4.VCC")
		(12 "In5.Cu" signal)
		(14 "In6.Cu" power "In6.VCC")
		(2 "B.Cu" signal)
		(9 "F.Adhes" user "F.Adhesive")
		(11 "B.Adhes" user "B.Adhesive")
		(13 "F.Paste" user)
		(15 "B.Paste" user)
		(5 "F.SilkS" user "F.Silkscreen")
		(7 "B.SilkS" user "B.Silkscreen")
		(1 "F.Mask" user)
		(3 "B.Mask" user)
		(17 "Dwgs.User" user "User.Drawings")
		(19 "Cmts.User" user "User.Comments")
		(21 "Eco1.User" user "User.Eco1")
		(23 "Eco2.User" user "User.Eco2")
		(25 "Edge.Cuts" user)
		(27 "Margin" user)
		(31 "F.CrtYd" user "F.Courtyard")
		(29 "B.CrtYd" user "B.Courtyard")
		(35 "F.Fab" user)
		(33 "B.Fab" user)
	)
	(footprint "antmicro-footprints:TP_SMD_1mm"
		(layer "F.Cu")
		(at 142.5 96.874)
		(property "Reference" "TP12"
			(at 0.4 0.326 0)
			(layer "F.SilkS")
			(effects
				(font
					(size 0.7 0.7)
					(thickness 0.15)
				)
				(justify left bottom)
			)
		)
		(property "Value" "TP_1mm_SMD"
			(at 0 1.4 0)
			(layer "F.Fab")
			(effects
				(font
					(size 0.7 0.7)
					(thickness 0.15)
				)
				(justify left bottom)
			)
		)
		(property "Description" "Test Point 1mm"
			(at 0 0 0)
			(layer "F.Fab")
			(hide yes)
			(effects
				(font
					(size 1.27 1.27)
					(thickness 0.15)
				)
			)
		)
		(property "Author" "Antmicro"
			(at 0 0 0)
			(layer "F.Fab")
			(hide yes)
			(effects
				(font
					(size 1 1)
					(thickness 0.15)
				)
			)
		)
		(property "License" "Apache-2.0"
			(at 0 0 0)
			(layer "F.Fab")
			(hide yes)
			(effects
				(font
					(size 1 1)
					(thickness 0.15)
				)
			)
		)
		(property "MPN" ""
			(at 0 0 0)
			(layer "F.Fab")
			(hide yes)
			(effects
				(font
					(size 1 1)
					(thickness 0.15)
				)
			)
		)
		(property "Manufacturer" ""
			(at 0 0 0)
			(layer "F.Fab")
			(hide yes)
			(effects
				(font
					(size 1 1)
					(thickness 0.15)
				)
			)
		)
		(sheetname "Supply")
		(sheetfile "supply.kicad_sch")
		(attr exclude_from_pos_files)
		(pad "1" smd circle
			(at 0 0)
			(size 1 1)
			(layers "F.Cu" "F.Mask")
			(net 470 "/Supply/VCC_IO_EN")
			(pinfunction "1")
			(pintype "passive")
		)
	)
	(footprint "antmicro-footprints:C_0402_1005Metric"
		(layer "F.Cu")
		(at 140.5 102.199 90)
		(descr "Capacitor SMD 0402")
		(tags "capacitor SMD 0402")
		(property "Reference" "C15"
			(at -1.101 -0.5 90)
			(layer "F.SilkS")
			(effects
				(font
					(size 0.7 0.7)
					(thickness 0.15)
				)
				(justify left bottom)
			)
		)
		(property "Value" "C_100n_6V3_0402"
			(at 0 1.4 90)
			(layer "F.Fab")
			(effects
				(font
					(size 0.7 0.7)
					(thickness 0.15)
				)
				(justify left bottom)
			)
		)
		(property "Description" " "
			(at 0 0 90)
			(layer "F.Fab")
			(hide yes)
			(effects
				(font
					(size 1.27 1.27)
					(thickness 0.15)
				)
			)
		)
		(property "Author" "Antmicro"
			(at 242.699 -38.301 0)
			(layer "F.Fab")
			(hide yes)
			(effects
				(font
					(size 1 1)
					(thickness 0.15)
				)
			)
		)
		(property "Dielectric" ""
			(at 242.699 -38.301 0)
			(layer "F.Fab")
			(hide yes)
			(effects
				(font
					(size 1 1)
					(thickness 0.15)
				)
			)
		)
		(property "License" "Apache-2.0"
			(at 242.699 -38.301 0)
			(layer "F.Fab")
			(hide yes)
			(effects
				(font
					(size 1 1)
					(thickness 0.15)
				)
			)
		)
		(property "MPN" "0402X104K6R3CT"
			(at 242.699 -38.301 0)
			(layer "F.Fab")
			(hide yes)
			(effects
				(font
					(size 1 1)
					(thickness 0.15)
				)
			)
		)
		(property "Manufacturer" "Walsin"
			(at 242.699 -38.301 0)
			(layer "F.Fab")
			(hide yes)
			(effects
				(font
					(size 1 1)
					(thickness 0.15)
				)
			)
		)
		(property "Val" "100n"
			(at 242.699 -38.301 0)
			(layer "F.Fab")
			(hide yes)
			(effects
				(font
					(size 1 1)
					(thickness 0.15)
				)
			)
		)
		(property "Voltage" ""
			(at 242.699 -38.301 0)
			(layer "F.Fab")
			(hide yes)
			(effects
				(font
					(size 1 1)
					(thickness 0.15)
				)
			)
		)
		(sheetname "Interfaces")
		(sheetfile "interfaces.kicad_sch")
		(attr smd)
		(fp_rect
			(start -0.94 -0.47)
			(end 0.94 0.47)
			(stroke
				(width 0.05)
				(type solid)
			)
			(fill no)
			(layer "F.CrtYd")
		)
		(fp_rect
			(start -0.499 -0.249)
			(end 0.499 0.249)
			(stroke
				(width 0.15)
				(type solid)
			)
			(fill no)
			(layer "F.Fab")
		)
		(pad "1" smd roundrect
			(at -0.484 0 90)
			(size 0.59 0.64)
			(layers "F.Cu" "F.Mask" "F.Paste")
			(roundrect_rratio 0.25)
			(net 459 "3V3_SYS")
			(pintype "passive")
		)
		(pad "2" smd roundrect
			(at 0.484 0 90)
			(size 0.59 0.64)
			(layers "F.Cu" "F.Mask" "F.Paste")
			(roundrect_rratio 0.25)
			(net 5 "GND")
			(pintype "passive")
		)
	)
	(footprint "antmicro-footprints:C_0603_1608Metric"
		(layer "F.Cu")
		(at 157.2 57.1 90)
		(descr "Capacitor SMD 0603")
		(tags "capacitor 0603")
		(property "Reference" "C139"
			(at -1.4 1.3 90)
			(layer "F.SilkS")
			(effects
				(font
					(size 0.7 0.7)
					(thickness 0.15)
				)
				(justify left bottom)
			)
		)
		(property "Value" "C_10n_0603"
			(at 0 1.6 90)
			(layer "F.Fab")
			(effects
				(font
					(size 0.7 0.7)
					(thickness 0.15)
				)
				(justify left bottom)
			)
		)
		(property "Description" " "
			(at 0 0 90)
			(layer "F.Fab")
			(hide yes)
			(effects
				(font
					(size 1.27 1.27)
					(thickness 0.15)
				)
			)
		)
		(property "Author" "Antmicro"
			(at 214.3 -100.1 0)
			(layer "F.Fab")
			(hide yes)
			(effects
				(font
					(size 1 1)
					(thickness 0.15)
				)
			)
		)
		(property "Dielectric" ""
			(at 214.3 -100.1 0)
			(layer "F.Fab")
			(hide yes)
			(effects
				(font
					(size 1 1)
					(thickness 0.15)
				)
			)
		)
		(property "License" "Apache-2.0"
			(at 214.3 -100.1 0)
			(layer "F.Fab")
			(hide yes)
			(effects
				(font
					(size 1 1)
					(thickness 0.15)
				)
			)
		)
		(property "MPN" "06031C103JAT2A"
			(at 214.3 -100.1 0)
			(layer "F.Fab")
			(hide yes)
			(effects
				(font
					(size 1 1)
					(thickness 0.15)
				)
			)
		)
		(property "Manufacturer" "AVX"
			(at 214.3 -100.1 0)
			(layer "F.Fab")
			(hide yes)
			(effects
				(font
					(size 1 1)
					(thickness 0.15)
				)
			)
		)
		(property "Val" "10n"
			(at 214.3 -100.1 0)
			(layer "F.Fab")
			(hide yes)
			(effects
				(font
					(size 1 1)
					(thickness 0.15)
				)
			)
		)
		(property "Voltage" ""
			(at 214.3 -100.1 0)
			(layer "F.Fab")
			(hide yes)
			(effects
				(font
					(size 1 1)
					(thickness 0.15)
				)
			)
		)
		(sheetname "Supply")
		(sheetfile "supply.kicad_sch")
		(attr smd)
		(fp_line
			(start -0.3 -0.3)
			(end 0.3 -0.3)
			(stroke
				(width 0.15)
				(type solid)
			)
			(layer "F.SilkS")
		)
		(fp_line
			(start -0.3 0.3)
			(end 0.3 0.3)
			(stroke
				(width 0.15)
				(type solid)
			)
			(layer "F.SilkS")
		)
		(fp_rect
			(start -1.24 -0.7)
			(end 1.24 0.7)
			(stroke
				(width 0.05)
				(type solid)
			)
			(fill no)
			(layer "F.CrtYd")
		)
		(fp_rect
			(start -0.8 -0.4)
			(end 0.8 0.4)
			(stroke
				(width 0.15)
				(type solid)
			)
			(fill no)
			(layer "F.Fab")
		)
		(pad "1" smd roundrect
			(at -0.7 0 90)
			(size 0.6 0.8)
			(layers "F.Cu" "F.Mask" "F.Paste")
			(roundrect_rratio 0.2)
			(net 66 "VDDQ")
			(pintype "passive")
		)
		(pad "2" smd roundrect
			(at 0.7 0 90)
			(size 0.6 0.8)
			(layers "F.Cu" "F.Mask" "F.Paste")
			(roundrect_rratio 0.2)
			(net 5 "GND")
			(pintype "passive")
		)
	)
	(footprint "antmicro-footprints:PinHeader_1x3_P2.54mm_Drill1.1mm"
		(layer "F.Cu")
		(at 213.196328 89.610008 90)
		(property "Reference" "MODE1"
			(at 0.710008 -1.868328 90)
			(layer "F.SilkS")
			(effects
				(font
					(size 0.7 0.7)
					(thickness 0.15)
				)
				(justify left bottom)
			)
		)
		(property "Value" "PinHeader_1x3_P2.54mm_Drill1.1mm"
			(at -1.6 2.7 90)
			(layer "F.Fab")
			(effects
				(font
					(size 0.7 0.7)
					(thickness 0.15)
				)
				(justify left bottom)
			)
		)
		(property "Description" "Pin Header, Vertical, Board-to-Board, 2.54 mm, 1 Rows, 3 Contacts, Through Hole Straight, WR-PHD"
			(at 0 0 90)
			(layer "F.Fab")
			(hide yes)
			(effects
				(font
					(size 1.27 1.27)
					(thickness 0.15)
				)
			)
		)
		(property "Author" "Antmicro"
			(at 302.806336 -123.58632 0)
			(layer "F.Fab")
			(hide yes)
			(effects
				(font
					(size 1 1)
					(thickness 0.15)
				)
			)
		)
		(property "License" "Apache-2.0"
			(at 302.806336 -123.58632 0)
			(layer "F.Fab")
			(hide yes)
			(effects
				(font
					(size 1 1)
					(thickness 0.15)
				)
			)
		)
		(property "MPN" "61300311121"
			(at 302.806336 -123.58632 0)
			(layer "F.Fab")
			(hide yes)
			(effects
				(font
					(size 1 1)
					(thickness 0.15)
				)
			)
		)
		(property "Manufacturer" "Würth Elektronik"
			(at 302.806336 -123.58632 0)
			(layer "F.Fab")
			(hide yes)
			(effects
				(font
					(size 1 1)
					(thickness 0.15)
				)
			)
		)
		(property "VSD_class" "IO Header"
			(at 302.806336 -123.58632 0)
			(layer "F.Fab")
			(hide yes)
			(effects
				(font
					(size 1 1)
					(thickness 0.15)
				)
			)
		)
		(sheetname "Config SPI flash")
		(sheetfile "config-spi.kicad_sch")
		(attr through_hole)
		(fp_line
			(start 6.499 -1.401)
			(end 5.999 -1.401)
			(stroke
				(width 0.15)
				(type solid)
			)
			(layer "F.SilkS")
		)
		(fp_line
			(start 6.499 -1.401)
			(end 6.499 -0.902)
			(stroke
				(width 0.15)
				(type solid)
			)
			(layer "F.SilkS")
		)
		(fp_line
			(start -1.401 -1.401)
			(end -0.902 -1.401)
			(stroke
				(width 0.15)
				(type solid)
			)
			(layer "F.SilkS")
		)
		(fp_line
			(start -1.401 -1.401)
			(end -1.401 -0.902)
			(stroke
				(width 0.15)
				(type solid)
			)
			(layer "F.SilkS")
		)
		(fp_line
			(start 6.499 1.398)
			(end 6.499 0.9)
			(stroke
				(width 0.15)
				(type solid)
			)
			(layer "F.SilkS")
		)
		(fp_line
			(start 6.499 1.398)
			(end 5.999 1.398)
			(stroke
				(width 0.15)
				(type solid)
			)
			(layer "F.SilkS")
		)
		(fp_line
			(start -1.401 1.398)
			(end -1.401 0.9)
			(stroke
				(width 0.15)
				(type solid)
			)
			(layer "F.SilkS")
		)
		(fp_line
			(start -1.401 1.398)
			(end -0.902 1.398)
			(stroke
				(width 0.15)
				(type solid)
			)
			(layer "F.SilkS")
		)
		(fp_line
			(start 6.58 -1.52)
			(end 6.58 1.5)
			(stroke
				(width 0.05)
				(type solid)
			)
			(layer "F.CrtYd")
		)
		(fp_line
			(start -1.52 -1.52)
			(end 6.58 -1.52)
			(stroke
				(width 0.05)
				(type solid)
			)
			(layer "F.CrtYd")
		)
		(fp_line
			(start -1.52 -1.52)
			(end -1.52 1.5)
			(stroke
				(width 0.05)
				(type solid)
			)
			(layer "F.CrtYd")
		)
		(fp_line
			(start -1.52 1.5)
			(end 6.58 1.5)
			(stroke
				(width 0.05)
				(type solid)
			)
			(layer "F.CrtYd")
		)
		(fp_line
			(start 6.349 -1.27)
			(end 6.349 1.269)
			(stroke
				(width 0.15)
				(type solid)
			)
			(layer "F.Fab")
		)
		(fp_line
			(start -1.27 -1.27)
			(end 6.349 -1.27)
			(stroke
				(width 0.15)
				(type solid)
			)
			(layer "F.Fab")
		)
		(fp_line
			(start -1.27 -1.27)
			(end -1.27 1.269)
			(stroke
				(width 0.15)
				(type solid)
			)
			(layer "F.Fab")
		)
		(fp_line
			(start -1.27 1.269)
			(end 6.349 1.269)
			(stroke
				(width 0.15)
				(type solid)
			)
			(layer "F.Fab")
		)
		(pad "1" thru_hole rect
			(at 0 0 90)
			(size 1.7 1.7)
			(drill 1.1)
			(layers "*.Cu" "*.Mask")
			(remove_unused_layers no)
			(net 5 "GND")
			(pintype "passive")
		)
		(pad "2" thru_hole circle
			(at 2.539 0 90)
			(size 1.7 1.7)
			(drill 1.1)
			(layers "*.Cu" "*.Mask")
			(remove_unused_layers no)
			(net 14 "MODE2")
			(pintype "passive")
		)
		(pad "3" thru_hole circle
			(at 5.078 0 90)
			(size 1.7 1.7)
			(drill 1.1)
			(layers "*.Cu" "*.Mask")
			(remove_unused_layers no)
			(net 459 "3V3_SYS")
			(pintype "passive")
		)
	)
	(footprint "antmicro-footprints:PinHeader_1x3_P2.54mm_Drill1.1mm"
		(layer "F.Cu")
		(at 164.936328 120.547157 90)
		(property "Reference" "J8"
			(at 5.485157 -1.8 90)
			(layer "F.SilkS")
			(effects
				(font
					(size 0.7 0.7)
					(thickness 0.15)
				)
				(justify left bottom)
			)
		)
		(property "Value" "PinHeader_1x3_P2.54mm_Drill1.1mm"
			(at -1.6 2.7 90)
			(layer "F.Fab")
			(effects
				(font
					(size 0.7 0.7)
					(thickness 0.15)
				)
				(justify left bottom)
			)
		)
		(property "Description" "Pin Header, Vertical, Board-to-Board, 2.54 mm, 1 Rows, 3 Contacts, Through Hole Straight, WR-PHD"
			(at 0 0 90)
			(layer "F.Fab")
			(hide yes)
			(effects
				(font
					(size 1.27 1.27)
					(thickness 0.15)
				)
			)
		)
		(property "Author" "Antmicro"
			(at 285.483485 -44.389171 0)
			(layer "F.Fab")
			(hide yes)
			(effects
				(font
					(size 1 1)
					(thickness 0.15)
				)
			)
		)
		(property "License" "Apache-2.0"
			(at 285.483485 -44.389171 0)
			(layer "F.Fab")
			(hide yes)
			(effects
				(font
					(size 1 1)
					(thickness 0.15)
				)
			)
		)
		(property "MPN" "61300311121"
			(at 285.483485 -44.389171 0)
			(layer "F.Fab")
			(hide yes)
			(effects
				(font
					(size 1 1)
					(thickness 0.15)
				)
			)
		)
		(property "Manufacturer" "Würth Elektronik"
			(at 285.483485 -44.389171 0)
			(layer "F.Fab")
			(hide yes)
			(effects
				(font
					(size 1 1)
					(thickness 0.15)
				)
			)
		)
		(property "VSD_class" "IO Header"
			(at 285.483485 -44.389171 0)
			(layer "F.Fab")
			(hide yes)
			(effects
				(font
					(size 1 1)
					(thickness 0.15)
				)
			)
		)
		(sheetname "Supply")
		(sheetfile "supply.kicad_sch")
		(attr through_hole)
		(fp_line
			(start 6.499 -1.401)
			(end 5.999 -1.401)
			(stroke
				(width 0.15)
				(type solid)
			)
			(layer "F.SilkS")
		)
		(fp_line
			(start 6.499 -1.401)
			(end 6.499 -0.902)
			(stroke
				(width 0.15)
				(type solid)
			)
			(layer "F.SilkS")
		)
		(fp_line
			(start -1.401 -1.401)
			(end -0.902 -1.401)
			(stroke
				(width 0.15)
				(type solid)
			)
			(layer "F.SilkS")
		)
		(fp_line
			(start -1.401 -1.401)
			(end -1.401 -0.902)
			(stroke
				(width 0.15)
				(type solid)
			)
			(layer "F.SilkS")
		)
		(fp_line
			(start 6.499 1.398)
			(end 6.499 0.9)
			(stroke
				(width 0.15)
				(type solid)
			)
			(layer "F.SilkS")
		)
		(fp_line
			(start 6.499 1.398)
			(end 5.999 1.398)
			(stroke
				(width 0.15)
				(type solid)
			)
			(layer "F.SilkS")
		)
		(fp_line
			(start -1.401 1.398)
			(end -1.401 0.9)
			(stroke
				(width 0.15)
				(type solid)
			)
			(layer "F.SilkS")
		)
		(fp_line
			(start -1.401 1.398)
			(end -0.902 1.398)
			(stroke
				(width 0.15)
				(type solid)
			)
			(layer "F.SilkS")
		)
		(fp_line
			(start 6.58 -1.52)
			(end 6.58 1.5)
			(stroke
				(width 0.05)
				(type solid)
			)
			(layer "F.CrtYd")
		)
		(fp_line
			(start -1.52 -1.52)
			(end 6.58 -1.52)
			(stroke
				(width 0.05)
				(type solid)
			)
			(layer "F.CrtYd")
		)
		(fp_line
			(start -1.52 -1.52)
			(end -1.52 1.5)
			(stroke
				(width 0.05)
				(type solid)
			)
			(layer "F.CrtYd")
		)
		(fp_line
			(start -1.52 1.5)
			(end 6.58 1.5)
			(stroke
				(width 0.05)
				(type solid)
			)
			(layer "F.CrtYd")
		)
		(fp_line
			(start 6.349 -1.27)
			(end 6.349 1.269)
			(stroke
				(width 0.15)
				(type solid)
			)
			(layer "F.Fab")
		)
		(fp_line
			(start -1.27 -1.27)
			(end 6.349 -1.27)
			(stroke
				(width 0.15)
				(type solid)
			)
			(layer "F.Fab")
		)
		(fp_line
			(start -1.27 -1.27)
			(end -1.27 1.269)
			(stroke
				(width 0.15)
				(type solid)
			)
			(layer "F.Fab")
		)
		(fp_line
			(start -1.27 1.269)
			(end 6.349 1.269)
			(stroke
				(width 0.15)
				(type solid)
			)
			(layer "F.Fab")
		)
		(pad "1" thru_hole rect
			(at 0 0 90)
			(size 1.7 1.7)
			(drill 1.1)
			(layers "*.Cu" "*.Mask")
			(remove_unused_layers no)
			(net 463 "VCC5V0_INT")
			(pintype "passive")
		)
		(pad "2" thru_hole circle
			(at 2.539 0 90)
			(size 1.7 1.7)
			(drill 1.1)
			(layers "*.Cu" "*.Mask")
			(remove_unused_layers no)
			(net 603 "unconnected-(J8-Pad2)")
			(pintype "passive+no_connect")
		)
		(pad "3" thru_hole circle
			(at 5.078 0 90)
			(size 1.7 1.7)
			(drill 1.1)
			(layers "*.Cu" "*.Mask")
			(remove_unused_layers no)
			(net 5 "GND")
			(pintype "passive")
		)
	)
)
